# S9S_MB_2U (Grand Teton) — schematic netlist excerpt (pin names and nets, part order shuffled) for the footprints in the layout excerpt that follows; sources: Cadence DE-HDL packaged netlist, KiCad conversion of 03242023_DA0F0TMBIJ0_F0T_Motherboard_J_brd_V01_OCP.brd

R3224  Q_RES  2K 1% CHIP  pkg 0402LF  page 236 : A = SMB_S3M_CPU1_PIROM_3V3AUX_SCL ; B = P3V3_AUX
C1976  Q_CAP  1000PF 50V 5% EMPTY  pkg 0402  page 147 : A = GPU_FPGA_OVERT_ISO_N ; B = GND

(kicad_pcb
	(version 20260206)
	(generator "pcbnew")
	(generator_version "10.0")
	(general
		(thickness 1.6)
		(legacy_teardrops no)
	)
	(paper "A4")
	(title_block
		(title "03242023_DA0F0TMBIJ0_F0T_Motherboard_J_brd_V01_OCP.brd")
		(comment 1 "Grand Teton / footprints 839-840 of 6105")
	)
	(layers
		(0 "F.Cu" signal "TOP")
		(4 "In1.Cu" signal "GND")
		(6 "In2.Cu" signal "IN1")
		(8 "In3.Cu" signal "GND1")
		(10 "In4.Cu" signal "IN2")
		(12 "In5.Cu" signal "GND2")
		(14 "In6.Cu" signal "IN3")
		(16 "In7.Cu" signal "GND3")
		(18 "In8.Cu" signal "VCC")
		(20 "In9.Cu" signal "VCC1")
		(22 "In10.Cu" signal "GND4")
		(24 "In11.Cu" signal "IN4")
		(26 "In12.Cu" signal "GND5")
		(28 "In13.Cu" signal "IN5")
		(30 "In14.Cu" signal "GND6")
		(32 "In15.Cu" signal "IN6")
		(34 "In16.Cu" signal "GND7")
		(2 "B.Cu" signal "BOTTOM")
		(9 "F.Adhes" user "F.Adhesive")
		(11 "B.Adhes" user "B.Adhesive")
		(13 "F.Paste" user "Package Geometry/Pastemask Top")
		(15 "B.Paste" user "Package Geometry/Pastemask Bottom")
		(5 "F.SilkS" user "Ref Des/Silkscreen Top")
		(7 "B.SilkS" user "Ref Des/Silkscreen Bottom")
		(1 "F.Mask" user "Board Geometry/Soldermask Top")
		(3 "B.Mask" user "Board Geometry/Soldermask Bottom")
		(17 "Dwgs.User" user "User.Drawings")
		(19 "Cmts.User" user "User.Comments")
		(21 "Eco1.User" user "User.Eco1")
		(23 "Eco2.User" user "User.Eco2")
		(25 "Edge.Cuts" user "Board Geometry/Outline")
		(27 "Margin" user)
		(31 "F.CrtYd" user "Package Geometry/Place Bound Top")
		(29 "B.CrtYd" user "Package Geometry/Place Bound Bottom")
		(35 "F.Fab" user "Ref Des/Assembly Top")
		(33 "B.Fab" user "Ref Des/Assembly Bottom")
	)
	(footprint ""
		(layer "F.Cu")
		(at 424.204892 -394.603478 180)
		(property "Reference" "C1976"
			(at 0 0 180)
			(layer "F.SilkS")
			(hide yes)
			(effects
				(font
					(size 1.27 1.27)
				)
			)
		)
		(property "Value" ""
			(at 0 0 180)
			(layer "F.Fab")
			(effects
				(font
					(size 1.27 1.27)
				)
			)
		)
		(duplicate_pad_numbers_are_jumpers no)
		(fp_line
			(start 0.7874 0.4064)
			(end -0.7874 0.4064)
			(stroke
				(width 0.1524)
				(type default)
			)
			(layer "F.SilkS")
		)
		(fp_line
			(start 0.7874 -0.4064)
			(end 0.7874 0.4064)
			(stroke
				(width 0.1524)
				(type default)
			)
			(layer "F.SilkS")
		)
		(fp_line
			(start -0.7874 0.4064)
			(end -0.7874 -0.4064)
			(stroke
				(width 0.1524)
				(type default)
			)
			(layer "F.SilkS")
		)
		(fp_line
			(start -0.7874 -0.4064)
			(end 0.7874 -0.4064)
			(stroke
				(width 0.1524)
				(type default)
			)
			(layer "F.SilkS")
		)
		(fp_line
			(start 0.67945 0.3048)
			(end 0.120396 0.3048)
			(stroke
				(width 0.1)
				(type default)
			)
			(layer "F.Fab")
		)
		(fp_line
			(start 0.67945 -0.3048)
			(end 0.67945 0.3048)
			(stroke
				(width 0.1)
				(type default)
			)
			(layer "F.Fab")
		)
		(fp_line
			(start 0.12065 -0.2794)
			(end 0.12065 -0.3048)
			(stroke
				(width 0.1)
				(type default)
			)
			(layer "F.Fab")
		)
		(fp_line
			(start 0.12065 -0.3048)
			(end 0.67945 -0.3048)
			(stroke
				(width 0.1)
				(type default)
			)
			(layer "F.Fab")
		)
		(fp_line
			(start 0.120396 0.3048)
			(end 0.120396 0.2794)
			(stroke
				(width 0.1)
				(type default)
			)
			(layer "F.Fab")
		)
		(fp_line
			(start 0.120396 0.2794)
			(end -0.12065 0.2794)
			(stroke
				(width 0.1)
				(type default)
			)
			(layer "F.Fab")
		)
		(fp_line
			(start -0.12065 0.3048)
			(end -0.67945 0.3048)
			(stroke
				(width 0.1)
				(type default)
			)
			(layer "F.Fab")
		)
		(fp_line
			(start -0.12065 0.2794)
			(end -0.12065 0.3048)
			(stroke
				(width 0.1)
				(type default)
			)
			(layer "F.Fab")
		)
		(fp_line
			(start -0.12065 -0.2794)
			(end 0.12065 -0.2794)
			(stroke
				(width 0.1)
				(type default)
			)
			(layer "F.Fab")
		)
		(fp_line
			(start -0.12065 -0.305054)
			(end -0.12065 -0.2794)
			(stroke
				(width 0.1)
				(type default)
			)
			(layer "F.Fab")
		)
		(fp_line
			(start -0.67945 0.3048)
			(end -0.67945 -0.305054)
			(stroke
				(width 0.1)
				(type default)
			)
			(layer "F.Fab")
		)
		(fp_line
			(start -0.67945 -0.305054)
			(end -0.12065 -0.305054)
			(stroke
				(width 0.1)
				(type default)
			)
			(layer "F.Fab")
		)
		(pad "1" smd circle
			(at -0.40005 0 180)
			(size 0 0)
			(layers "F.Cu" "F.Mask" "F.Paste")
			(net "GPU_FPGA_OVERT_ISO_N")
		)
		(pad "2" smd circle
			(at 0.40005 0 180)
			(size 0 0)
			(layers "F.Cu" "F.Mask" "F.Paste")
			(net "GND")
		)
	)
	(footprint ""
		(layer "F.Cu")
		(at 160.311084 -81.91246 -90)
		(property "Reference" "R3224"
			(at 0 0 270)
			(layer "F.SilkS")
			(hide yes)
			(effects
				(font
					(size 1.27 1.27)
				)
			)
		)
		(property "Value" ""
			(at 0 0 270)
			(layer "F.Fab")
			(effects
				(font
					(size 1.27 1.27)
				)
			)
		)
		(duplicate_pad_numbers_are_jumpers no)
		(fp_line
			(start -0.7874 0.4064)
			(end -0.7874 -0.4064)
			(stroke
				(width 0.1524)
				(type default)
			)
			(layer "F.SilkS")
		)
		(fp_line
			(start 0.7874 0.4064)
			(end -0.7874 0.4064)
			(stroke
				(width 0.1524)
				(type default)
			)
			(layer "F.SilkS")
		)
		(fp_line
			(start -0.7874 -0.4064)
			(end 0.7874 -0.4064)
			(stroke
				(width 0.1524)
				(type default)
			)
			(layer "F.SilkS")
		)
		(fp_line
			(start 0.7874 -0.4064)
			(end 0.7874 0.4064)
			(stroke
				(width 0.1524)
				(type default)
			)
			(layer "F.SilkS")
		)
		(fp_line
			(start -0.67945 0.3048)
			(end -0.67945 -0.305054)
			(stroke
				(width 0.1)
				(type default)
			)
			(layer "F.Fab")
		)
		(fp_line
			(start -0.12065 0.3048)
			(end -0.67945 0.3048)
			(stroke
				(width 0.1)
				(type default)
			)
			(layer "F.Fab")
		)
		(fp_line
			(start 0.120396 0.3048)
			(end 0.120396 0.2794)
			(stroke
				(width 0.1)
				(type default)
			)
			(layer "F.Fab")
		)
		(fp_line
			(start 0.67945 0.3048)
			(end 0.120396 0.3048)
			(stroke
				(width 0.1)
				(type default)
			)
			(layer "F.Fab")
		)
		(fp_line
			(start -0.12065 0.2794)
			(end -0.12065 0.3048)
			(stroke
				(width 0.1)
				(type default)
			)
			(layer "F.Fab")
		)
		(fp_line
			(start 0.120396 0.2794)
			(end -0.12065 0.2794)
			(stroke
				(width 0.1)
				(type default)
			)
			(layer "F.Fab")
		)
		(fp_line
			(start -0.12065 -0.2794)
			(end 0.12065 -0.2794)
			(stroke
				(width 0.1)
				(type default)
			)
			(layer "F.Fab")
		)
		(fp_line
			(start 0.12065 -0.2794)
			(end 0.12065 -0.3048)
			(stroke
				(width 0.1)
				(type default)
			)
			(layer "F.Fab")
		)
		(fp_line
			(start 0.12065 -0.3048)
			(end 0.67945 -0.3048)
			(stroke
				(width 0.1)
				(type default)
			)
			(layer "F.Fab")
		)
		(fp_line
			(start 0.67945 -0.3048)
			(end 0.67945 0.3048)
			(stroke
				(width 0.1)
				(type default)
			)
			(layer "F.Fab")
		)
		(fp_line
			(start -0.67945 -0.305054)
			(end -0.12065 -0.305054)
			(stroke
				(width 0.1)
				(type default)
			)
			(layer "F.Fab")
		)
		(fp_line
			(start -0.12065 -0.305054)
			(end -0.12065 -0.2794)
			(stroke
				(width 0.1)
				(type default)
			)
			(layer "F.Fab")
		)
		(pad "1" smd circle
			(at -0.40005 0 270)
			(size 0 0)
			(layers "F.Cu" "F.Mask" "F.Paste")
			(net "SMB_S3M_CPU1_PIROM_3V3AUX_SCL")
		)
		(pad "2" smd circle
			(at 0.40005 0 270)
			(size 0 0)
			(layers "F.Cu" "F.Mask" "F.Paste")
			(net "P3V3_AUX")
		)
	)
)
